# S9S_MB_2U (Grand Teton) — schematic netlist excerpt (pin names and nets, part order shuffled) for the footprints in the layout excerpt that follows; sources: Cadence DE-HDL packaged netlist, KiCad conversion of 03242023_DA0F0TMBIJ0_F0T_Motherboard_J_brd_V01_OCP.brd

R4581  Q_RES  1K 1% CHIP  pkg 0402LF  page 195 : A = FM_BOARD_BMC_SKU_ID4 ; B = GND
R3134  Q_RES  1K 1% CHIP  pkg 0402LF  page 162 : A = P3V3_AUX ; B = OCP_V3_2_PRSNT2_R_N

(kicad_pcb
	(version 20260206)
	(generator "pcbnew")
	(generator_version "10.0")
	(general
		(thickness 1.6)
		(legacy_teardrops no)
	)
	(paper "A4")
	(title_block
		(title "03242023_DA0F0TMBIJ0_F0T_Motherboard_J_brd_V01_OCP.brd")
		(comment 1 "Grand Teton / footprints 1644-1645 of 6105")
	)
	(layers
		(0 "F.Cu" signal "TOP")
		(4 "In1.Cu" signal "GND")
		(6 "In2.Cu" signal "IN1")
		(8 "In3.Cu" signal "GND1")
		(10 "In4.Cu" signal "IN2")
		(12 "In5.Cu" signal "GND2")
		(14 "In6.Cu" signal "IN3")
		(16 "In7.Cu" signal "GND3")
		(18 "In8.Cu" signal "VCC")
		(20 "In9.Cu" signal "VCC1")
		(22 "In10.Cu" signal "GND4")
		(24 "In11.Cu" signal "IN4")
		(26 "In12.Cu" signal "GND5")
		(28 "In13.Cu" signal "IN5")
		(30 "In14.Cu" signal "GND6")
		(32 "In15.Cu" signal "IN6")
		(34 "In16.Cu" signal "GND7")
		(2 "B.Cu" signal "BOTTOM")
		(9 "F.Adhes" user "F.Adhesive")
		(11 "B.Adhes" user "B.Adhesive")
		(13 "F.Paste" user "Package Geometry/Pastemask Top")
		(15 "B.Paste" user "Package Geometry/Pastemask Bottom")
		(5 "F.SilkS" user "Ref Des/Silkscreen Top")
		(7 "B.SilkS" user "Ref Des/Silkscreen Bottom")
		(1 "F.Mask" user "Board Geometry/Soldermask Top")
		(3 "B.Mask" user "Board Geometry/Soldermask Bottom")
		(17 "Dwgs.User" user "User.Drawings")
		(19 "Cmts.User" user "User.Comments")
		(21 "Eco1.User" user "User.Eco1")
		(23 "Eco2.User" user "User.Eco2")
		(25 "Edge.Cuts" user "Board Geometry/Outline")
		(27 "Margin" user)
		(31 "F.CrtYd" user "Package Geometry/Place Bound Top")
		(29 "B.CrtYd" user "Package Geometry/Place Bound Bottom")
		(35 "F.Fab" user "Ref Des/Assembly Top")
		(33 "B.Fab" user "Ref Des/Assembly Bottom")
	)
	(footprint ""
		(layer "F.Cu")
		(at 20.60956 -72.710548)
		(property "Reference" "R3134"
			(at 0 0 0)
			(layer "F.SilkS")
			(hide yes)
			(effects
				(font
					(size 1.27 1.27)
				)
			)
		)
		(property "Value" ""
			(at 0 0 0)
			(layer "F.Fab")
			(effects
				(font
					(size 1.27 1.27)
				)
			)
		)
		(duplicate_pad_numbers_are_jumpers no)
		(fp_line
			(start -0.7874 -0.4064)
			(end 0.7874 -0.4064)
			(stroke
				(width 0.1524)
				(type default)
			)
			(layer "F.SilkS")
		)
		(fp_line
			(start -0.7874 0.4064)
			(end -0.7874 -0.4064)
			(stroke
				(width 0.1524)
				(type default)
			)
			(layer "F.SilkS")
		)
		(fp_line
			(start 0.7874 -0.4064)
			(end 0.7874 0.4064)
			(stroke
				(width 0.1524)
				(type default)
			)
			(layer "F.SilkS")
		)
		(fp_line
			(start 0.7874 0.4064)
			(end -0.7874 0.4064)
			(stroke
				(width 0.1524)
				(type default)
			)
			(layer "F.SilkS")
		)
		(fp_line
			(start -0.67945 -0.305054)
			(end -0.12065 -0.305054)
			(stroke
				(width 0.1)
				(type default)
			)
			(layer "F.Fab")
		)
		(fp_line
			(start -0.67945 0.3048)
			(end -0.67945 -0.305054)
			(stroke
				(width 0.1)
				(type default)
			)
			(layer "F.Fab")
		)
		(fp_line
			(start -0.12065 -0.305054)
			(end -0.12065 -0.2794)
			(stroke
				(width 0.1)
				(type default)
			)
			(layer "F.Fab")
		)
		(fp_line
			(start -0.12065 -0.2794)
			(end 0.12065 -0.2794)
			(stroke
				(width 0.1)
				(type default)
			)
			(layer "F.Fab")
		)
		(fp_line
			(start -0.12065 0.2794)
			(end -0.12065 0.3048)
			(stroke
				(width 0.1)
				(type default)
			)
			(layer "F.Fab")
		)
		(fp_line
			(start -0.12065 0.3048)
			(end -0.67945 0.3048)
			(stroke
				(width 0.1)
				(type default)
			)
			(layer "F.Fab")
		)
		(fp_line
			(start 0.120396 0.2794)
			(end -0.12065 0.2794)
			(stroke
				(width 0.1)
				(type default)
			)
			(layer "F.Fab")
		)
		(fp_line
			(start 0.120396 0.3048)
			(end 0.120396 0.2794)
			(stroke
				(width 0.1)
				(type default)
			)
			(layer "F.Fab")
		)
		(fp_line
			(start 0.12065 -0.3048)
			(end 0.67945 -0.3048)
			(stroke
				(width 0.1)
				(type default)
			)
			(layer "F.Fab")
		)
		(fp_line
			(start 0.12065 -0.2794)
			(end 0.12065 -0.3048)
			(stroke
				(width 0.1)
				(type default)
			)
			(layer "F.Fab")
		)
		(fp_line
			(start 0.67945 -0.3048)
			(end 0.67945 0.3048)
			(stroke
				(width 0.1)
				(type default)
			)
			(layer "F.Fab")
		)
		(fp_line
			(start 0.67945 0.3048)
			(end 0.120396 0.3048)
			(stroke
				(width 0.1)
				(type default)
			)
			(layer "F.Fab")
		)
		(pad "1" smd circle
			(at -0.40005 0)
			(size 0 0)
			(layers "F.Cu" "F.Mask" "F.Paste")
			(net "P3V3_AUX")
		)
		(pad "2" smd circle
			(at 0.40005 0)
			(size 0 0)
			(layers "F.Cu" "F.Mask" "F.Paste")
			(net "OCP_V3_2_PRSNT2_R_N")
		)
	)
	(footprint ""
		(layer "F.Cu")
		(at 172.8724 -94.338648 90)
		(property "Reference" "R4581"
			(at 0 0 90)
			(layer "F.SilkS")
			(hide yes)
			(effects
				(font
					(size 1.27 1.27)
				)
			)
		)
		(property "Value" ""
			(at 0 0 90)
			(layer "F.Fab")
			(effects
				(font
					(size 1.27 1.27)
				)
			)
		)
		(duplicate_pad_numbers_are_jumpers no)
		(fp_line
			(start 0.7874 -0.4064)
			(end 0.7874 0.4064)
			(stroke
				(width 0.1524)
				(type default)
			)
			(layer "F.SilkS")
		)
		(fp_line
			(start -0.7874 -0.4064)
			(end 0.7874 -0.4064)
			(stroke
				(width 0.1524)
				(type default)
			)
			(layer "F.SilkS")
		)
		(fp_line
			(start 0.7874 0.4064)
			(end -0.7874 0.4064)
			(stroke
				(width 0.1524)
				(type default)
			)
			(layer "F.SilkS")
		)
		(fp_line
			(start -0.7874 0.4064)
			(end -0.7874 -0.4064)
			(stroke
				(width 0.1524)
				(type default)
			)
			(layer "F.SilkS")
		)
		(fp_line
			(start -0.12065 -0.305054)
			(end -0.12065 -0.2794)
			(stroke
				(width 0.1)
				(type default)
			)
			(layer "F.Fab")
		)
		(fp_line
			(start -0.67945 -0.305054)
			(end -0.12065 -0.305054)
			(stroke
				(width 0.1)
				(type default)
			)
			(layer "F.Fab")
		)
		(fp_line
			(start 0.67945 -0.3048)
			(end 0.67945 0.3048)
			(stroke
				(width 0.1)
				(type default)
			)
			(layer "F.Fab")
		)
		(fp_line
			(start 0.12065 -0.3048)
			(end 0.67945 -0.3048)
			(stroke
				(width 0.1)
				(type default)
			)
			(layer "F.Fab")
		)
		(fp_line
			(start 0.12065 -0.2794)
			(end 0.12065 -0.3048)
			(stroke
				(width 0.1)
				(type default)
			)
			(layer "F.Fab")
		)
		(fp_line
			(start -0.12065 -0.2794)
			(end 0.12065 -0.2794)
			(stroke
				(width 0.1)
				(type default)
			)
			(layer "F.Fab")
		)
		(fp_line
			(start 0.120396 0.2794)
			(end -0.12065 0.2794)
			(stroke
				(width 0.1)
				(type default)
			)
			(layer "F.Fab")
		)
		(fp_line
			(start -0.12065 0.2794)
			(end -0.12065 0.3048)
			(stroke
				(width 0.1)
				(type default)
			)
			(layer "F.Fab")
		)
		(fp_line
			(start 0.67945 0.3048)
			(end 0.120396 0.3048)
			(stroke
				(width 0.1)
				(type default)
			)
			(layer "F.Fab")
		)
		(fp_line
			(start 0.120396 0.3048)
			(end 0.120396 0.2794)
			(stroke
				(width 0.1)
				(type default)
			)
			(layer "F.Fab")
		)
		(fp_line
			(start -0.12065 0.3048)
			(end -0.67945 0.3048)
			(stroke
				(width 0.1)
				(type default)
			)
			(layer "F.Fab")
		)
		(fp_line
			(start -0.67945 0.3048)
			(end -0.67945 -0.305054)
			(stroke
				(width 0.1)
				(type default)
			)
			(layer "F.Fab")
		)
		(pad "1" smd rect
			(at -0.40005 0 270)
			(size 0.4572 0.508)
			(layers "F.Cu" "F.Mask" "F.Paste")
			(net "FM_BOARD_BMC_SKU_ID4")
		)
		(pad "2" smd rect
			(at 0.40005 0 270)
			(size 0.4572 0.508)
			(layers "F.Cu" "F.Mask" "F.Paste")
			(net "GND")
		)
	)
)
